(kicad_pcb
	(version 20260206)
	(generator "pcbnew")
	(generator_version "10.0")
	(general
		(thickness 1.6)
		(legacy_teardrops no)
	)
	(paper "A4")
	(title_block
		(title "Bryce Canyon_IOM_IOC_16318-2_OCP.brd")
		(comment 1 "Bryce Canyon / footprints 423-429 of 1605")
	)
	(layers
		(0 "F.Cu" signal "TOP")
		(4 "In1.Cu" signal "L2GND")
		(6 "In2.Cu" signal "L3")
		(8 "In3.Cu" signal "L4VCC")
		(10 "In4.Cu" signal "L5VCC")
		(12 "In5.Cu" signal "L6")
		(14 "In6.Cu" signal "L7GND")
		(2 "B.Cu" signal "BOTTOM")
		(9 "F.Adhes" user "F.Adhesive")
		(11 "B.Adhes" user "B.Adhesive")
		(13 "F.Paste" user "Package Geometry/Pastemask Top")
		(15 "B.Paste" user "Package Geometry/Pastemask Bottom")
		(5 "F.SilkS" user "Ref Des/Silkscreen Top")
		(7 "B.SilkS" user "Ref Des/Silkscreen Bottom")
		(1 "F.Mask" user "Board Geometry/Soldermask Top")
		(3 "B.Mask" user "Board Geometry/Soldermask Bottom")
		(17 "Dwgs.User" user "User.Drawings")
		(19 "Cmts.User" user "User.Comments")
		(21 "Eco1.User" user "User.Eco1")
		(23 "Eco2.User" user "User.Eco2")
		(25 "Edge.Cuts" user "Board Geometry/Outline")
		(27 "Margin" user)
		(31 "F.CrtYd" user "Package Geometry/Place Bound Top")
		(29 "B.CrtYd" user "Package Geometry/Place Bound Bottom")
		(35 "F.Fab" user "Ref Des/Assembly Top")
		(33 "B.Fab" user "Ref Des/Assembly Bottom")
	)
	(footprint ""
		(layer "F.Cu")
		(at 158.40964 -140.955522 -90)
		(property "Reference" "C208"
			(at 0 0 270)
			(layer "F.SilkS")
			(hide yes)
			(effects
				(font
					(size 1.27 1.27)
				)
			)
		)
		(property "Value" "SC3300P50V2KX-1GP"
			(at 1.1811 -2.7051 270)
			(unlocked yes)
			(layer "F.Fab")
			(hide yes)
			(effects
				(font
					(size 1.016 1.016)
					(thickness 0.1524)
				)
			)
		)
		(property "Device Type" "C402H22"
			(at 1.1811 -4.2291 270)
			(unlocked yes)
			(layer "F.Fab")
			(hide yes)
			(effects
				(font
					(size 1.016 1.016)
					(thickness 0.1524)
				)
			)
		)
		(duplicate_pad_numbers_are_jumpers no)
		(fp_rect
			(start -0.4318 0.9525)
			(end 0.4318 -0.9525)
			(stroke
				(width 0)
				(type default)
			)
			(fill no)
			(layer "F.CrtYd")
		)
		(fp_rect
			(start -0.4318 0.9525)
			(end 0.4318 -0.9525)
			(stroke
				(width 0)
				(type default)
			)
			(fill no)
			(layer "F.Fab")
		)
		(pad "1" smd custom
			(at 0 -0.4445 270)
			(size 0.1524 0.1524)
			(layers "F.Cu" "F.Mask" "F.Paste")
			(net "P1V8_STBY_SS")
			(options
				(clearance outline)
				(anchor circle)
			)
			(primitives
				(gr_poly
					(pts
						(arc
							(start 0.3048 -0.2032)
							(mid 0.275042 -0.275042)
							(end 0.2032 -0.3048)
						)
						(arc
							(start -0.2032 -0.3048)
							(mid -0.275042 -0.275042)
							(end -0.3048 -0.2032)
						)
						(arc
							(start -0.3048 0.2032)
							(mid -0.275042 0.275042)
							(end -0.2032 0.3048)
						)
						(arc
							(start 0.2032 0.3048)
							(mid 0.275042 0.275042)
							(end 0.3048 0.2032)
						)
					)
					(width 0)
					(fill yes)
				)
			)
		)
		(pad "2" smd custom
			(at 0 0.4445 270)
			(size 0.1524 0.1524)
			(layers "F.Cu" "F.Mask" "F.Paste")
			(net "AGND_P1V8_STBY")
			(options
				(clearance outline)
				(anchor circle)
			)
			(primitives
				(gr_poly
					(pts
						(arc
							(start 0.3048 -0.2032)
							(mid 0.275042 -0.275042)
							(end 0.2032 -0.3048)
						)
						(arc
							(start -0.2032 -0.3048)
							(mid -0.275042 -0.275042)
							(end -0.3048 -0.2032)
						)
						(arc
							(start -0.3048 0.2032)
							(mid -0.275042 0.275042)
							(end -0.2032 0.3048)
						)
						(arc
							(start 0.2032 0.3048)
							(mid 0.275042 0.275042)
							(end 0.3048 0.2032)
						)
					)
					(width 0)
					(fill yes)
				)
			)
		)
	)
	(footprint ""
		(layer "F.Cu")
		(at 99.601782 -151.43226)
		(property "Reference" "R36"
			(at 0 0 0)
			(layer "F.SilkS")
			(hide yes)
			(effects
				(font
					(size 1.27 1.27)
				)
			)
		)
		(property "Value" "4K7R2F-GP"
			(at 0.064008 -3.993896 0)
			(unlocked yes)
			(layer "F.Fab")
			(hide yes)
			(effects
				(font
					(size 1.016 1.016)
					(thickness 0.1524)
				)
			)
		)
		(property "Device Type" "R402H16"
			(at 0.064008 -5.517896 0)
			(unlocked yes)
			(layer "F.Fab")
			(hide yes)
			(effects
				(font
					(size 1.016 1.016)
					(thickness 0.1524)
				)
			)
		)
		(duplicate_pad_numbers_are_jumpers no)
		(fp_line
			(start -0.508 -0.9398)
			(end -0.508 0.9398)
			(stroke
				(width 0.1524)
				(type default)
			)
			(layer "F.SilkS")
		)
		(fp_line
			(start 0.508 -0.9398)
			(end -0.508 -0.9398)
			(stroke
				(width 0.1524)
				(type default)
			)
			(layer "F.SilkS")
		)
		(fp_rect
			(start -0.508 0.9398)
			(end 0.508 -0.9398)
			(stroke
				(width 0)
				(type default)
			)
			(fill no)
			(layer "F.CrtYd")
		)
		(fp_rect
			(start -0.508 0.9398)
			(end 0.508 -0.9398)
			(stroke
				(width 0)
				(type default)
			)
			(fill no)
			(layer "F.Fab")
		)
		(pad "1" smd custom
			(at 0 -0.4445)
			(size 0.1397 0.1397)
			(layers "F.Cu" "F.Mask" "F.Paste")
			(net "P3V3_STBY")
			(options
				(clearance outline)
				(anchor circle)
			)
			(primitives
				(gr_poly
					(pts
						(arc
							(start -0.1778 -0.2794)
							(mid -0.249642 -0.249642)
							(end -0.2794 -0.1778)
						)
						(arc
							(start -0.2794 0.1778)
							(mid -0.249642 0.249642)
							(end -0.1778 0.2794)
						)
						(arc
							(start 0.1778 0.2794)
							(mid 0.249642 0.249642)
							(end 0.2794 0.1778)
						)
						(arc
							(start 0.2794 -0.1778)
							(mid 0.249642 -0.249642)
							(end 0.1778 -0.2794)
						)
					)
					(width 0)
					(fill yes)
				)
			)
		)
		(pad "2" smd custom
			(at 0 0.4445)
			(size 0.1397 0.1397)
			(layers "F.Cu" "F.Mask" "F.Paste")
			(net "USB_EN_4")
			(options
				(clearance outline)
				(anchor circle)
			)
			(primitives
				(gr_poly
					(pts
						(arc
							(start -0.1778 -0.2794)
							(mid -0.249642 -0.249642)
							(end -0.2794 -0.1778)
						)
						(arc
							(start -0.2794 0.1778)
							(mid -0.249642 0.249642)
							(end -0.1778 0.2794)
						)
						(arc
							(start 0.1778 0.2794)
							(mid 0.249642 0.249642)
							(end 0.2794 0.1778)
						)
						(arc
							(start 0.2794 -0.1778)
							(mid 0.249642 -0.249642)
							(end 0.1778 -0.2794)
						)
					)
					(width 0)
					(fill yes)
				)
			)
		)
	)
	(footprint ""
		(layer "F.Cu")
		(at 98.9076 -153.9748 -90)
		(property "Reference" "R19"
			(at 0 0 270)
			(layer "F.SilkS")
			(hide yes)
			(effects
				(font
					(size 1.27 1.27)
				)
			)
		)
		(property "Value" "4K7R2F-GP"
			(at 0.064008 -3.993896 270)
			(unlocked yes)
			(layer "F.Fab")
			(hide yes)
			(effects
				(font
					(size 1.016 1.016)
					(thickness 0.1524)
				)
			)
		)
		(property "Device Type" "R402H16"
			(at 0.064008 -5.517896 270)
			(unlocked yes)
			(layer "F.Fab")
			(hide yes)
			(effects
				(font
					(size 1.016 1.016)
					(thickness 0.1524)
				)
			)
		)
		(duplicate_pad_numbers_are_jumpers no)
		(fp_line
			(start -0.508 -0.9398)
			(end -0.508 0.9398)
			(stroke
				(width 0.1524)
				(type default)
			)
			(layer "F.SilkS")
		)
		(fp_line
			(start 0.508 -0.9398)
			(end -0.508 -0.9398)
			(stroke
				(width 0.1524)
				(type default)
			)
			(layer "F.SilkS")
		)
		(fp_rect
			(start -0.508 0.9398)
			(end 0.508 -0.9398)
			(stroke
				(width 0)
				(type default)
			)
			(fill no)
			(layer "F.CrtYd")
		)
		(fp_rect
			(start -0.508 0.9398)
			(end 0.508 -0.9398)
			(stroke
				(width 0)
				(type default)
			)
			(fill no)
			(layer "F.Fab")
		)
		(pad "1" smd custom
			(at 0 -0.4445 270)
			(size 0.1397 0.1397)
			(layers "F.Cu" "F.Mask" "F.Paste")
			(net "P3V3_STBY")
			(options
				(clearance outline)
				(anchor circle)
			)
			(primitives
				(gr_poly
					(pts
						(arc
							(start -0.1778 -0.2794)
							(mid -0.249642 -0.249642)
							(end -0.2794 -0.1778)
						)
						(arc
							(start -0.2794 0.1778)
							(mid -0.249642 0.249642)
							(end -0.1778 0.2794)
						)
						(arc
							(start 0.1778 0.2794)
							(mid 0.249642 0.249642)
							(end 0.2794 0.1778)
						)
						(arc
							(start 0.2794 -0.1778)
							(mid 0.249642 -0.249642)
							(end 0.1778 -0.2794)
						)
					)
					(width 0)
					(fill yes)
				)
			)
		)
		(pad "2" smd custom
			(at 0 0.4445 270)
			(size 0.1397 0.1397)
			(layers "F.Cu" "F.Mask" "F.Paste")
			(net "CFG_SEL0")
			(options
				(clearance outline)
				(anchor circle)
			)
			(primitives
				(gr_poly
					(pts
						(arc
							(start -0.1778 -0.2794)
							(mid -0.249642 -0.249642)
							(end -0.2794 -0.1778)
						)
						(arc
							(start -0.2794 0.1778)
							(mid -0.249642 0.249642)
							(end -0.1778 0.2794)
						)
						(arc
							(start 0.1778 0.2794)
							(mid 0.249642 0.249642)
							(end 0.2794 0.1778)
						)
						(arc
							(start 0.2794 -0.1778)
							(mid 0.249642 -0.249642)
							(end 0.1778 -0.2794)
						)
					)
					(width 0)
					(fill yes)
				)
			)
		)
	)
	(footprint ""
		(layer "F.Cu")
		(at 94.765876 -21.51253 90)
		(property "Reference" "D17"
			(at 0 0 90)
			(layer "F.SilkS")
			(hide yes)
			(effects
				(font
					(size 1.27 1.27)
				)
			)
		)
		(property "Value" "PESD5V0S1BL-1-GP"
			(at 1.8923 -1.5621 90)
			(unlocked yes)
			(layer "F.Fab")
			(hide yes)
			(effects
				(font
					(size 1.016 1.016)
					(thickness 0.1524)
				)
			)
		)
		(property "Device Type" "SOD882-10D6-1H20"
			(at 1.8923 -3.0861 90)
			(unlocked yes)
			(layer "F.Fab")
			(hide yes)
			(effects
				(font
					(size 1.016 1.016)
					(thickness 0.1524)
				)
			)
		)
		(duplicate_pad_numbers_are_jumpers no)
		(fp_line
			(start -0.3048 -0.9271)
			(end 0.3048 -0.9271)
			(stroke
				(width 0.254)
				(type default)
			)
			(layer "F.SilkS")
		)
		(fp_rect
			(start -0.2921 0.4953)
			(end 0.2921 -0.4953)
			(stroke
				(width 0)
				(type default)
			)
			(fill no)
			(layer "F.CrtYd")
		)
		(fp_poly
			(pts
				(xy -0.4318 0.8001) (xy -0.4318 -0.266192) (xy -0.2921 -0.266192) (xy -0.2921 0.4953) (xy 0.2921 0.4953)
				(xy 0.2921 -0.4953) (xy -0.2921 -0.4953) (xy -0.2921 -0.2667) (xy -0.4318 -0.2667) (xy -0.4318 -0.8001)
				(xy 0.4318 -0.8001) (xy 0.4318 0.8001)
			)
			(stroke
				(width 0)
				(type default)
			)
			(fill no)
			(layer "F.CrtYd")
		)
		(fp_rect
			(start -0.4318 0.8001)
			(end 0.4318 -0.8001)
			(stroke
				(width 0)
				(type default)
			)
			(fill no)
			(layer "F.Fab")
		)
		(pad "1" smd custom
			(at 0 -0.4445 90)
			(size 0.1143 0.1143)
			(layers "F.Cu" "F.Mask" "F.Paste")
			(net "UART_IOM_RX")
			(options
				(clearance outline)
				(anchor circle)
			)
			(primitives
				(gr_poly
					(pts
						(arc
							(start -0.2032 0.2286)
							(mid -0.275042 0.198842)
							(end -0.3048 0.127)
						)
						(arc
							(start -0.3048 -0.127)
							(mid -0.275042 -0.198842)
							(end -0.2032 -0.2286)
						)
						(arc
							(start 0.2032 -0.2286)
							(mid 0.275042 -0.198842)
							(end 0.3048 -0.127)
						)
						(arc
							(start 0.3048 0.127)
							(mid 0.275042 0.198842)
							(end 0.2032 0.2286)
						)
					)
					(width 0)
					(fill yes)
				)
			)
		)
		(pad "2" smd custom
			(at 0 0.4445 90)
			(size 0.1143 0.1143)
			(layers "F.Cu" "F.Mask" "F.Paste")
			(net "GND")
			(options
				(clearance outline)
				(anchor circle)
			)
			(primitives
				(gr_poly
					(pts
						(arc
							(start 0.2032 -0.2286)
							(mid 0.275042 -0.198842)
							(end 0.3048 -0.127)
						)
						(arc
							(start 0.3048 0.127)
							(mid 0.275042 0.198842)
							(end 0.2032 0.2286)
						)
						(arc
							(start -0.2032 0.2286)
							(mid -0.275042 0.198842)
							(end -0.3048 0.127)
						)
						(arc
							(start -0.3048 -0.127)
							(mid -0.275042 -0.198842)
							(end -0.2032 -0.2286)
						)
					)
					(width 0)
					(fill yes)
				)
			)
		)
	)
	(footprint ""
		(layer "F.Cu")
		(at 87.702898 -136.971786 180)
		(property "Reference" "R133"
			(at 0 0 180)
			(layer "F.SilkS")
			(hide yes)
			(effects
				(font
					(size 1.27 1.27)
				)
			)
		)
		(property "Value" "8K2R2J-3-GP"
			(at 0.064008 -3.993896 180)
			(unlocked yes)
			(layer "F.Fab")
			(hide yes)
			(effects
				(font
					(size 1.016 1.016)
					(thickness 0.1524)
				)
			)
		)
		(property "Device Type" "R402H16"
			(at 0.064008 -5.517896 180)
			(unlocked yes)
			(layer "F.Fab")
			(hide yes)
			(effects
				(font
					(size 1.016 1.016)
					(thickness 0.1524)
				)
			)
		)
		(duplicate_pad_numbers_are_jumpers no)
		(fp_line
			(start 0.508 -0.9398)
			(end -0.508 -0.9398)
			(stroke
				(width 0.1524)
				(type default)
			)
			(layer "F.SilkS")
		)
		(fp_line
			(start -0.508 -0.9398)
			(end -0.508 0.9398)
			(stroke
				(width 0.1524)
				(type default)
			)
			(layer "F.SilkS")
		)
		(fp_rect
			(start -0.508 0.9398)
			(end 0.508 -0.9398)
			(stroke
				(width 0)
				(type default)
			)
			(fill no)
			(layer "F.CrtYd")
		)
		(fp_rect
			(start -0.508 0.9398)
			(end 0.508 -0.9398)
			(stroke
				(width 0)
				(type default)
			)
			(fill no)
			(layer "F.Fab")
		)
		(pad "1" smd custom
			(at 0 -0.4445 180)
			(size 0.1397 0.1397)
			(layers "F.Cu" "F.Mask" "F.Paste")
			(net "P3V3_STBY")
			(options
				(clearance outline)
				(anchor circle)
			)
			(primitives
				(gr_poly
					(pts
						(arc
							(start -0.1778 -0.2794)
							(mid -0.249642 -0.249642)
							(end -0.2794 -0.1778)
						)
						(arc
							(start -0.2794 0.1778)
							(mid -0.249642 0.249642)
							(end -0.1778 0.2794)
						)
						(arc
							(start 0.1778 0.2794)
							(mid 0.249642 0.249642)
							(end 0.2794 0.1778)
						)
						(arc
							(start 0.2794 -0.1778)
							(mid 0.249642 -0.249642)
							(end 0.1778 -0.2794)
						)
					)
					(width 0)
					(fill yes)
				)
			)
		)
		(pad "2" smd custom
			(at 0 0.4445 180)
			(size 0.1397 0.1397)
			(layers "F.Cu" "F.Mask" "F.Paste")
			(net "EEPROM_A0")
			(options
				(clearance outline)
				(anchor circle)
			)
			(primitives
				(gr_poly
					(pts
						(arc
							(start -0.1778 -0.2794)
							(mid -0.249642 -0.249642)
							(end -0.2794 -0.1778)
						)
						(arc
							(start -0.2794 0.1778)
							(mid -0.249642 0.249642)
							(end -0.1778 0.2794)
						)
						(arc
							(start 0.1778 0.2794)
							(mid 0.249642 0.249642)
							(end 0.2794 0.1778)
						)
						(arc
							(start 0.2794 -0.1778)
							(mid 0.249642 -0.249642)
							(end 0.1778 -0.2794)
						)
					)
					(width 0)
					(fill yes)
				)
			)
		)
	)
	(footprint ""
		(layer "F.Cu")
		(at 199.5424 -28.9179)
		(property "Reference" "Q27"
			(at 0 0 0)
			(layer "F.SilkS")
			(hide yes)
			(effects
				(font
					(size 1.27 1.27)
				)
			)
		)
		(property "Value" "SSM3K324R-GP"
			(at 0.127 -8.9662 0)
			(unlocked yes)
			(layer "F.Fab")
			(hide yes)
			(effects
				(font
					(size 1.016 1.016)
					(thickness 0.1524)
				)
			)
		)
		(property "Device Type" "SOT23DGS2D4H35"
			(at 0.127 -10.4902 0)
			(unlocked yes)
			(layer "F.Fab")
			(hide yes)
			(effects
				(font
					(size 1.016 1.016)
					(thickness 0.1524)
				)
			)
		)
		(duplicate_pad_numbers_are_jumpers no)
		(fp_line
			(start -1.651 -1.778)
			(end -1.651 1.778)
			(stroke
				(width 0.1524)
				(type default)
			)
			(layer "F.SilkS")
		)
		(fp_line
			(start -1.651 1.778)
			(end 1.651 1.778)
			(stroke
				(width 0.1524)
				(type default)
			)
			(layer "F.SilkS")
		)
		(fp_line
			(start 1.651 -1.778)
			(end -1.651 -1.778)
			(stroke
				(width 0.1524)
				(type default)
			)
			(layer "F.SilkS")
		)
		(fp_line
			(start 1.651 1.778)
			(end 1.651 -1.778)
			(stroke
				(width 0.1524)
				(type default)
			)
			(layer "F.SilkS")
		)
		(fp_poly
			(pts
				(xy -1.778 1.8796) (xy -1.778 -1.8796) (xy 1.778 -1.8796) (xy 1.778 1.8796)
			)
			(stroke
				(width 0)
				(type default)
			)
			(fill no)
			(layer "F.CrtYd")
		)
		(fp_poly
			(pts
				(xy -1.778 1.8796) (xy -1.778 -1.8796) (xy 1.778 -1.8796) (xy 1.778 1.8796)
			)
			(stroke
				(width 0)
				(type default)
			)
			(fill no)
			(layer "F.Fab")
		)
		(pad "D" smd custom
			(at 0 -0.9525)
			(size 0.1905 0.1905)
			(layers "F.Cu" "F.Mask" "F.Paste")
			(net "EXT2_LED_BLUE_G2")
			(options
				(clearance outline)
				(anchor circle)
			)
			(primitives
				(gr_poly
					(pts
						(arc
							(start -0.1778 0.5715)
							(mid -0.321484 0.511984)
							(end -0.381 0.3683)
						)
						(arc
							(start -0.381 -0.3683)
							(mid -0.321484 -0.511984)
							(end -0.1778 -0.5715)
						)
						(arc
							(start 0.1778 -0.5715)
							(mid 0.321484 -0.511984)
							(end 0.381 -0.3683)
						)
						(arc
							(start 0.381 0.3683)
							(mid 0.321484 0.511984)
							(end 0.1778 0.5715)
						)
					)
					(width 0)
					(fill yes)
				)
			)
		)
		(pad "G" smd custom
			(at -0.98425 0.9525)
			(size 0.1905 0.1905)
			(layers "F.Cu" "F.Mask" "F.Paste")
			(net "EXT2_LED_BLUE_G_Q27")
			(options
				(clearance outline)
				(anchor circle)
			)
			(primitives
				(gr_poly
					(pts
						(arc
							(start -0.1778 0.5715)
							(mid -0.321484 0.511984)
							(end -0.381 0.3683)
						)
						(arc
							(start -0.381 -0.3683)
							(mid -0.321484 -0.511984)
							(end -0.1778 -0.5715)
						)
						(arc
							(start 0.1778 -0.5715)
							(mid 0.321484 -0.511984)
							(end 0.381 -0.3683)
						)
						(arc
							(start 0.381 0.3683)
							(mid 0.321484 0.511984)
							(end 0.1778 0.5715)
						)
					)
					(width 0)
					(fill yes)
				)
			)
		)
		(pad "S" smd custom
			(at 0.98425 0.9525)
			(size 0.1905 0.1905)
			(layers "F.Cu" "F.Mask" "F.Paste")
			(net "GND")
			(options
				(clearance outline)
				(anchor circle)
			)
			(primitives
				(gr_poly
					(pts
						(arc
							(start -0.1778 0.5715)
							(mid -0.321484 0.511984)
							(end -0.381 0.3683)
						)
						(arc
							(start -0.381 -0.3683)
							(mid -0.321484 -0.511984)
							(end -0.1778 -0.5715)
						)
						(arc
							(start 0.1778 -0.5715)
							(mid 0.321484 -0.511984)
							(end 0.381 -0.3683)
						)
						(arc
							(start 0.381 0.3683)
							(mid 0.321484 0.511984)
							(end 0.1778 0.5715)
						)
					)
					(width 0)
					(fill yes)
				)
			)
		)
	)
	(footprint ""
		(layer "F.Cu")
		(at 84.983828 -85.349334 90)
		(property "Reference" "VIA14"
			(at 0 0 90)
			(layer "F.SilkS")
			(hide yes)
			(effects
				(font
					(size 1.27 1.27)
				)
			)
		)
		(property "Value" "85OHM-8L-1D6MM-L16L18-GP"
			(at 4.064 0.6096 90)
			(unlocked yes)
			(layer "F.Fab")
			(hide yes)
			(effects
				(font
					(size 1.016 1.016)
					(thickness 0.1524)
				)
			)
		)
		(property "Device Type" "VIA-PCIE-4P-368076"
			(at 4.064 -0.9144 90)
			(unlocked yes)
			(layer "F.Fab")
			(hide yes)
			(effects
				(font
					(size 1.016 1.016)
					(thickness 0.1524)
				)
			)
		)
		(duplicate_pad_numbers_are_jumpers no)
		(fp_rect
			(start -1.8415 0.381)
			(end 1.8415 -0.381)
			(stroke
				(width 0)
				(type default)
			)
			(fill no)
			(layer "F.CrtYd")
		)
		(fp_rect
			(start -1.8415 0.381)
			(end 1.8415 -0.381)
			(stroke
				(width 0)
				(type default)
			)
			(fill no)
			(layer "F.Fab")
		)
		(pad "1" thru_hole circle
			(at -1.4605 0 90)
			(size 0.508 0.508)
			(drill 0.254)
			(layers "*.Cu" "*.Mask")
			(remove_unused_layers no)
			(net "GND")
			(clearance 0.127)
			(thermal_gap 0.127)
		)
		(pad "2" thru_hole circle
			(at -0.4445 0 90)
			(size 0.508 0.508)
			(drill 0.254)
			(layers "*.Cu" "*.Mask")
			(remove_unused_layers no)
			(net "PCIE_IOM_TO_COMP_20_DP")
			(clearance 0.127)
			(thermal_gap 0.127)
		)
		(pad "3" thru_hole circle
			(at 0.4445 0 90)
			(size 0.508 0.508)
			(drill 0.254)
			(layers "*.Cu" "*.Mask")
			(remove_unused_layers no)
			(net "PCIE_IOM_TO_COMP_20_DN")
			(clearance 0.127)
			(thermal_gap 0.127)
		)
		(pad "4" thru_hole circle
			(at 1.4605 0 90)
			(size 0.508 0.508)
			(drill 0.254)
			(layers "*.Cu" "*.Mask")
			(remove_unused_layers no)
			(net "GND")
			(clearance 0.127)
			(thermal_gap 0.127)
		)
	)
)
